# Stackup_F0T_Management_Board_12L_1p6mm_IT-170GRA1_RG311_Rev0p2_20220715 的複本.xls — Special processing (pcb-stackup)
| Special processing : |  |
| Golden Finger(金手指) | Yes |
| VIPPO(Via in Pad樹脂填孔) | Yes |
| Back Drill(背鑽) with epoxy plug/fill | No |
| Back Drill(背鑽) without epoxy plug/fill | No |
| Laser Drill(HDI雷射鑽孔) | No |
| Low profile oxide(低棕化) | No |
